(kicad_pcb
	(version 20260206)
	(generator "pcbnew")
	(generator_version "10.0")
	(general
		(thickness 1.6)
		(legacy_teardrops no)
	)
	(paper "A4")
	(title_block
		(title "04192023_DAF0TMB3IC0_F0TG_MB_C_brd_V02_OCP.brd")
		(comment 1 "Grand Teton / footprints 4905-4911 of 8354")
	)
	(layers
		(0 "F.Cu" signal "TOP")
		(4 "In1.Cu" signal "GND")
		(6 "In2.Cu" signal "IN1")
		(8 "In3.Cu" signal "GND1")
		(10 "In4.Cu" signal "IN2")
		(12 "In5.Cu" signal "GND2")
		(14 "In6.Cu" signal "IN3")
		(16 "In7.Cu" signal "GND3")
		(18 "In8.Cu" signal "VCC")
		(20 "In9.Cu" signal "VCC1")
		(22 "In10.Cu" signal "GND4")
		(24 "In11.Cu" signal "IN4")
		(26 "In12.Cu" signal "GND5")
		(28 "In13.Cu" signal "IN5")
		(30 "In14.Cu" signal "GND6")
		(32 "In15.Cu" signal "IN6")
		(34 "In16.Cu" signal "GND7")
		(2 "B.Cu" signal "BOTTOM")
		(9 "F.Adhes" user "F.Adhesive")
		(11 "B.Adhes" user "B.Adhesive")
		(13 "F.Paste" user "Package Geometry/Pastemask Top")
		(15 "B.Paste" user "Package Geometry/Pastemask Bottom")
		(5 "F.SilkS" user "Ref Des/Silkscreen Top")
		(7 "B.SilkS" user "Ref Des/Silkscreen Bottom")
		(1 "F.Mask" user "Board Geometry/Soldermask Top")
		(3 "B.Mask" user "Board Geometry/Soldermask Bottom")
		(17 "Dwgs.User" user "User.Drawings")
		(19 "Cmts.User" user "User.Comments")
		(21 "Eco1.User" user "User.Eco1")
		(23 "Eco2.User" user "User.Eco2")
		(25 "Edge.Cuts" user "Board Geometry/Outline")
		(27 "Margin" user)
		(31 "F.CrtYd" user "Package Geometry/Place Bound Top")
		(29 "B.CrtYd" user "Package Geometry/Place Bound Bottom")
		(35 "F.Fab" user "Ref Des/Assembly Top")
		(33 "B.Fab" user "Ref Des/Assembly Bottom")
	)
	(footprint ""
		(layer "F.Cu")
		(at 376.809 -426.339 180)
		(property "Reference" "R1206"
			(at 0 0 180)
			(layer "F.SilkS")
			(hide yes)
			(effects
				(font
					(size 1.27 1.27)
				)
			)
		)
		(property "Value" ""
			(at 0 0 180)
			(layer "F.Fab")
			(effects
				(font
					(size 1.27 1.27)
				)
			)
		)
		(duplicate_pad_numbers_are_jumpers no)
		(fp_line
			(start 0.32512 0.175006)
			(end -0.32512 0.175006)
			(stroke
				(width 0.1)
				(type default)
			)
			(layer "F.Fab")
		)
		(fp_line
			(start 0.32512 -0.175006)
			(end 0.32512 0.175006)
			(stroke
				(width 0.1)
				(type default)
			)
			(layer "F.Fab")
		)
		(fp_line
			(start -0.32512 0.175006)
			(end -0.32512 -0.175006)
			(stroke
				(width 0.1)
				(type default)
			)
			(layer "F.Fab")
		)
		(fp_line
			(start -0.32512 -0.175006)
			(end 0.32512 -0.175006)
			(stroke
				(width 0.1)
				(type default)
			)
			(layer "F.Fab")
		)
		(pad "1" smd rect
			(at -0.2667 0 180)
			(size 0.3048 0.381)
			(layers "F.Cu" "F.Mask" "F.Paste")
			(net "RST_SMB_RT_ROM_R1_N")
		)
		(pad "2" smd rect
			(at 0.2667 0)
			(size 0.3048 0.381)
			(layers "F.Cu" "F.Mask" "F.Paste")
			(net "FM_SMB_RT_ROM_MUX7_SEL")
		)
	)
	(footprint ""
		(layer "F.Cu")
		(at 412.472886 -74.864468 180)
		(property "Reference" "R3501"
			(at 0 0 180)
			(layer "F.SilkS")
			(hide yes)
			(effects
				(font
					(size 1.27 1.27)
				)
			)
		)
		(property "Value" ""
			(at 0 0 180)
			(layer "F.Fab")
			(effects
				(font
					(size 1.27 1.27)
				)
			)
		)
		(duplicate_pad_numbers_are_jumpers no)
		(fp_line
			(start 0.7874 0.4064)
			(end -0.7874 0.4064)
			(stroke
				(width 0.1524)
				(type default)
			)
			(layer "F.SilkS")
		)
		(fp_line
			(start 0.7874 -0.4064)
			(end 0.7874 0.4064)
			(stroke
				(width 0.1524)
				(type default)
			)
			(layer "F.SilkS")
		)
		(fp_line
			(start -0.7874 0.4064)
			(end -0.7874 -0.4064)
			(stroke
				(width 0.1524)
				(type default)
			)
			(layer "F.SilkS")
		)
		(fp_line
			(start -0.7874 -0.4064)
			(end 0.7874 -0.4064)
			(stroke
				(width 0.1524)
				(type default)
			)
			(layer "F.SilkS")
		)
		(fp_line
			(start 0.67945 0.3048)
			(end 0.120396 0.3048)
			(stroke
				(width 0.1)
				(type default)
			)
			(layer "F.Fab")
		)
		(fp_line
			(start 0.67945 -0.3048)
			(end 0.67945 0.3048)
			(stroke
				(width 0.1)
				(type default)
			)
			(layer "F.Fab")
		)
		(fp_line
			(start 0.12065 -0.2794)
			(end 0.12065 -0.3048)
			(stroke
				(width 0.1)
				(type default)
			)
			(layer "F.Fab")
		)
		(fp_line
			(start 0.12065 -0.3048)
			(end 0.67945 -0.3048)
			(stroke
				(width 0.1)
				(type default)
			)
			(layer "F.Fab")
		)
		(fp_line
			(start 0.120396 0.3048)
			(end 0.120396 0.2794)
			(stroke
				(width 0.1)
				(type default)
			)
			(layer "F.Fab")
		)
		(fp_line
			(start 0.120396 0.2794)
			(end -0.12065 0.2794)
			(stroke
				(width 0.1)
				(type default)
			)
			(layer "F.Fab")
		)
		(fp_line
			(start -0.12065 0.3048)
			(end -0.67945 0.3048)
			(stroke
				(width 0.1)
				(type default)
			)
			(layer "F.Fab")
		)
		(fp_line
			(start -0.12065 0.2794)
			(end -0.12065 0.3048)
			(stroke
				(width 0.1)
				(type default)
			)
			(layer "F.Fab")
		)
		(fp_line
			(start -0.12065 -0.2794)
			(end 0.12065 -0.2794)
			(stroke
				(width 0.1)
				(type default)
			)
			(layer "F.Fab")
		)
		(fp_line
			(start -0.12065 -0.305054)
			(end -0.12065 -0.2794)
			(stroke
				(width 0.1)
				(type default)
			)
			(layer "F.Fab")
		)
		(fp_line
			(start -0.67945 0.3048)
			(end -0.67945 -0.305054)
			(stroke
				(width 0.1)
				(type default)
			)
			(layer "F.Fab")
		)
		(fp_line
			(start -0.67945 -0.305054)
			(end -0.12065 -0.305054)
			(stroke
				(width 0.1)
				(type default)
			)
			(layer "F.Fab")
		)
		(pad "1" smd circle
			(at -0.40005 0 180)
			(size 0 0)
			(layers "F.Cu" "F.Mask" "F.Paste")
			(net "P3V3_OCP_SFF")
		)
		(pad "2" smd circle
			(at 0.40005 0 180)
			(size 0 0)
			(layers "F.Cu" "F.Mask" "F.Paste")
			(net "SMB_OCP_SFF_3V3AUX_BUF_SDA")
		)
	)
	(footprint ""
		(layer "F.Cu")
		(at 150.400258 -116.449094)
		(property "Reference" "R2230"
			(at 0 0 0)
			(layer "F.SilkS")
			(hide yes)
			(effects
				(font
					(size 1.27 1.27)
				)
			)
		)
		(property "Value" ""
			(at 0 0 0)
			(layer "F.Fab")
			(effects
				(font
					(size 1.27 1.27)
				)
			)
		)
		(duplicate_pad_numbers_are_jumpers no)
		(fp_line
			(start -0.7874 -0.4064)
			(end 0.7874 -0.4064)
			(stroke
				(width 0.1524)
				(type default)
			)
			(layer "F.SilkS")
		)
		(fp_line
			(start -0.7874 0.4064)
			(end -0.7874 -0.4064)
			(stroke
				(width 0.1524)
				(type default)
			)
			(layer "F.SilkS")
		)
		(fp_line
			(start 0.7874 -0.4064)
			(end 0.7874 0.4064)
			(stroke
				(width 0.1524)
				(type default)
			)
			(layer "F.SilkS")
		)
		(fp_line
			(start 0.7874 0.4064)
			(end -0.7874 0.4064)
			(stroke
				(width 0.1524)
				(type default)
			)
			(layer "F.SilkS")
		)
		(fp_line
			(start -0.67945 -0.305054)
			(end -0.12065 -0.305054)
			(stroke
				(width 0.1)
				(type default)
			)
			(layer "F.Fab")
		)
		(fp_line
			(start -0.67945 0.3048)
			(end -0.67945 -0.305054)
			(stroke
				(width 0.1)
				(type default)
			)
			(layer "F.Fab")
		)
		(fp_line
			(start -0.12065 -0.305054)
			(end -0.12065 -0.2794)
			(stroke
				(width 0.1)
				(type default)
			)
			(layer "F.Fab")
		)
		(fp_line
			(start -0.12065 -0.2794)
			(end 0.12065 -0.2794)
			(stroke
				(width 0.1)
				(type default)
			)
			(layer "F.Fab")
		)
		(fp_line
			(start -0.12065 0.2794)
			(end -0.12065 0.3048)
			(stroke
				(width 0.1)
				(type default)
			)
			(layer "F.Fab")
		)
		(fp_line
			(start -0.12065 0.3048)
			(end -0.67945 0.3048)
			(stroke
				(width 0.1)
				(type default)
			)
			(layer "F.Fab")
		)
		(fp_line
			(start 0.120396 0.2794)
			(end -0.12065 0.2794)
			(stroke
				(width 0.1)
				(type default)
			)
			(layer "F.Fab")
		)
		(fp_line
			(start 0.120396 0.3048)
			(end 0.120396 0.2794)
			(stroke
				(width 0.1)
				(type default)
			)
			(layer "F.Fab")
		)
		(fp_line
			(start 0.12065 -0.3048)
			(end 0.67945 -0.3048)
			(stroke
				(width 0.1)
				(type default)
			)
			(layer "F.Fab")
		)
		(fp_line
			(start 0.12065 -0.2794)
			(end 0.12065 -0.3048)
			(stroke
				(width 0.1)
				(type default)
			)
			(layer "F.Fab")
		)
		(fp_line
			(start 0.67945 -0.3048)
			(end 0.67945 0.3048)
			(stroke
				(width 0.1)
				(type default)
			)
			(layer "F.Fab")
		)
		(fp_line
			(start 0.67945 0.3048)
			(end 0.120396 0.3048)
			(stroke
				(width 0.1)
				(type default)
			)
			(layer "F.Fab")
		)
		(pad "1" smd circle
			(at -0.40005 0)
			(size 0 0)
			(layers "F.Cu" "F.Mask" "F.Paste")
			(net "P3V3_AUX")
		)
		(pad "2" smd circle
			(at 0.40005 0)
			(size 0 0)
			(layers "F.Cu" "F.Mask" "F.Paste")
			(net "A_P12V_STBY_FPH_GATE")
		)
	)
	(footprint ""
		(layer "F.Cu")
		(at 230.675688 -158.981648 180)
		(property "Reference" "C1523"
			(at 0 0 180)
			(layer "F.SilkS")
			(hide yes)
			(effects
				(font
					(size 1.27 1.27)
				)
			)
		)
		(property "Value" ""
			(at 0 0 180)
			(layer "F.Fab")
			(effects
				(font
					(size 1.27 1.27)
				)
			)
		)
		(duplicate_pad_numbers_are_jumpers no)
		(fp_line
			(start 0.7874 0.4064)
			(end -0.7874 0.4064)
			(stroke
				(width 0.1524)
				(type default)
			)
			(layer "F.SilkS")
		)
		(fp_line
			(start 0.7874 -0.4064)
			(end 0.7874 0.4064)
			(stroke
				(width 0.1524)
				(type default)
			)
			(layer "F.SilkS")
		)
		(fp_line
			(start -0.7874 0.4064)
			(end -0.7874 -0.4064)
			(stroke
				(width 0.1524)
				(type default)
			)
			(layer "F.SilkS")
		)
		(fp_line
			(start -0.7874 -0.4064)
			(end 0.7874 -0.4064)
			(stroke
				(width 0.1524)
				(type default)
			)
			(layer "F.SilkS")
		)
		(fp_line
			(start 0.67945 0.3048)
			(end 0.120396 0.3048)
			(stroke
				(width 0.1)
				(type default)
			)
			(layer "F.Fab")
		)
		(fp_line
			(start 0.67945 -0.3048)
			(end 0.67945 0.3048)
			(stroke
				(width 0.1)
				(type default)
			)
			(layer "F.Fab")
		)
		(fp_line
			(start 0.12065 -0.2794)
			(end 0.12065 -0.3048)
			(stroke
				(width 0.1)
				(type default)
			)
			(layer "F.Fab")
		)
		(fp_line
			(start 0.12065 -0.3048)
			(end 0.67945 -0.3048)
			(stroke
				(width 0.1)
				(type default)
			)
			(layer "F.Fab")
		)
		(fp_line
			(start 0.120396 0.3048)
			(end 0.120396 0.2794)
			(stroke
				(width 0.1)
				(type default)
			)
			(layer "F.Fab")
		)
		(fp_line
			(start 0.120396 0.2794)
			(end -0.12065 0.2794)
			(stroke
				(width 0.1)
				(type default)
			)
			(layer "F.Fab")
		)
		(fp_line
			(start -0.12065 0.3048)
			(end -0.67945 0.3048)
			(stroke
				(width 0.1)
				(type default)
			)
			(layer "F.Fab")
		)
		(fp_line
			(start -0.12065 0.2794)
			(end -0.12065 0.3048)
			(stroke
				(width 0.1)
				(type default)
			)
			(layer "F.Fab")
		)
		(fp_line
			(start -0.12065 -0.2794)
			(end 0.12065 -0.2794)
			(stroke
				(width 0.1)
				(type default)
			)
			(layer "F.Fab")
		)
		(fp_line
			(start -0.12065 -0.305054)
			(end -0.12065 -0.2794)
			(stroke
				(width 0.1)
				(type default)
			)
			(layer "F.Fab")
		)
		(fp_line
			(start -0.67945 0.3048)
			(end -0.67945 -0.305054)
			(stroke
				(width 0.1)
				(type default)
			)
			(layer "F.Fab")
		)
		(fp_line
			(start -0.67945 -0.305054)
			(end -0.12065 -0.305054)
			(stroke
				(width 0.1)
				(type default)
			)
			(layer "F.Fab")
		)
		(pad "1" smd circle
			(at -0.40005 0 180)
			(size 0 0)
			(layers "F.Cu" "F.Mask" "F.Paste")
			(net "PVDD18_S5_P0")
		)
		(pad "2" smd circle
			(at 0.40005 0 180)
			(size 0 0)
			(layers "F.Cu" "F.Mask" "F.Paste")
			(net "GND")
		)
	)
	(footprint ""
		(layer "F.Cu")
		(at 22.49297 -332.104746)
		(property "Reference" "PR227"
			(at 0 0 0)
			(layer "F.SilkS")
			(hide yes)
			(effects
				(font
					(size 1.27 1.27)
				)
			)
		)
		(property "Value" ""
			(at 0 0 0)
			(layer "F.Fab")
			(effects
				(font
					(size 1.27 1.27)
				)
			)
		)
		(duplicate_pad_numbers_are_jumpers no)
		(fp_line
			(start -0.7874 -0.4064)
			(end 0.7874 -0.4064)
			(stroke
				(width 0.1524)
				(type default)
			)
			(layer "F.SilkS")
		)
		(fp_line
			(start -0.7874 0.4064)
			(end -0.7874 -0.4064)
			(stroke
				(width 0.1524)
				(type default)
			)
			(layer "F.SilkS")
		)
		(fp_line
			(start 0.7874 -0.4064)
			(end 0.7874 0.4064)
			(stroke
				(width 0.1524)
				(type default)
			)
			(layer "F.SilkS")
		)
		(fp_line
			(start 0.7874 0.4064)
			(end -0.7874 0.4064)
			(stroke
				(width 0.1524)
				(type default)
			)
			(layer "F.SilkS")
		)
		(fp_line
			(start -0.67945 -0.305054)
			(end -0.12065 -0.305054)
			(stroke
				(width 0.1)
				(type default)
			)
			(layer "F.Fab")
		)
		(fp_line
			(start -0.67945 0.3048)
			(end -0.67945 -0.305054)
			(stroke
				(width 0.1)
				(type default)
			)
			(layer "F.Fab")
		)
		(fp_line
			(start -0.12065 -0.305054)
			(end -0.12065 -0.2794)
			(stroke
				(width 0.1)
				(type default)
			)
			(layer "F.Fab")
		)
		(fp_line
			(start -0.12065 -0.2794)
			(end 0.12065 -0.2794)
			(stroke
				(width 0.1)
				(type default)
			)
			(layer "F.Fab")
		)
		(fp_line
			(start -0.12065 0.2794)
			(end -0.12065 0.3048)
			(stroke
				(width 0.1)
				(type default)
			)
			(layer "F.Fab")
		)
		(fp_line
			(start -0.12065 0.3048)
			(end -0.67945 0.3048)
			(stroke
				(width 0.1)
				(type default)
			)
			(layer "F.Fab")
		)
		(fp_line
			(start 0.120396 0.2794)
			(end -0.12065 0.2794)
			(stroke
				(width 0.1)
				(type default)
			)
			(layer "F.Fab")
		)
		(fp_line
			(start 0.120396 0.3048)
			(end 0.120396 0.2794)
			(stroke
				(width 0.1)
				(type default)
			)
			(layer "F.Fab")
		)
		(fp_line
			(start 0.12065 -0.3048)
			(end 0.67945 -0.3048)
			(stroke
				(width 0.1)
				(type default)
			)
			(layer "F.Fab")
		)
		(fp_line
			(start 0.12065 -0.2794)
			(end 0.12065 -0.3048)
			(stroke
				(width 0.1)
				(type default)
			)
			(layer "F.Fab")
		)
		(fp_line
			(start 0.67945 -0.3048)
			(end 0.67945 0.3048)
			(stroke
				(width 0.1)
				(type default)
			)
			(layer "F.Fab")
		)
		(fp_line
			(start 0.67945 0.3048)
			(end 0.120396 0.3048)
			(stroke
				(width 0.1)
				(type default)
			)
			(layer "F.Fab")
		)
		(pad "1" smd circle
			(at -0.40005 0)
			(size 0 0)
			(layers "F.Cu" "F.Mask" "F.Paste")
			(net "VSENSE_PVDDIO_P1_DP")
		)
		(pad "2" smd circle
			(at 0.40005 0)
			(size 0 0)
			(layers "F.Cu" "F.Mask" "F.Paste")
			(net "PVDDIO_P1")
		)
	)
	(footprint ""
		(layer "F.Cu")
		(at 98.222562 -31.835598 -90)
		(property "Reference" "C6089"
			(at 0 0 270)
			(layer "F.SilkS")
			(hide yes)
			(effects
				(font
					(size 1.27 1.27)
				)
			)
		)
		(property "Value" ""
			(at 0 0 270)
			(layer "F.Fab")
			(effects
				(font
					(size 1.27 1.27)
				)
			)
		)
		(duplicate_pad_numbers_are_jumpers no)
		(fp_line
			(start -0.7874 0.4064)
			(end -0.7874 -0.4064)
			(stroke
				(width 0.1524)
				(type default)
			)
			(layer "F.SilkS")
		)
		(fp_line
			(start 0.7874 0.4064)
			(end -0.7874 0.4064)
			(stroke
				(width 0.1524)
				(type default)
			)
			(layer "F.SilkS")
		)
		(fp_line
			(start -0.7874 -0.4064)
			(end 0.7874 -0.4064)
			(stroke
				(width 0.1524)
				(type default)
			)
			(layer "F.SilkS")
		)
		(fp_line
			(start 0.7874 -0.4064)
			(end 0.7874 0.4064)
			(stroke
				(width 0.1524)
				(type default)
			)
			(layer "F.SilkS")
		)
		(fp_line
			(start -0.67945 0.3048)
			(end -0.67945 -0.305054)
			(stroke
				(width 0.1)
				(type default)
			)
			(layer "F.Fab")
		)
		(fp_line
			(start -0.12065 0.3048)
			(end -0.67945 0.3048)
			(stroke
				(width 0.1)
				(type default)
			)
			(layer "F.Fab")
		)
		(fp_line
			(start 0.120396 0.3048)
			(end 0.120396 0.2794)
			(stroke
				(width 0.1)
				(type default)
			)
			(layer "F.Fab")
		)
		(fp_line
			(start 0.67945 0.3048)
			(end 0.120396 0.3048)
			(stroke
				(width 0.1)
				(type default)
			)
			(layer "F.Fab")
		)
		(fp_line
			(start -0.12065 0.2794)
			(end -0.12065 0.3048)
			(stroke
				(width 0.1)
				(type default)
			)
			(layer "F.Fab")
		)
		(fp_line
			(start 0.120396 0.2794)
			(end -0.12065 0.2794)
			(stroke
				(width 0.1)
				(type default)
			)
			(layer "F.Fab")
		)
		(fp_line
			(start -0.12065 -0.2794)
			(end 0.12065 -0.2794)
			(stroke
				(width 0.1)
				(type default)
			)
			(layer "F.Fab")
		)
		(fp_line
			(start 0.12065 -0.2794)
			(end 0.12065 -0.3048)
			(stroke
				(width 0.1)
				(type default)
			)
			(layer "F.Fab")
		)
		(fp_line
			(start 0.12065 -0.3048)
			(end 0.67945 -0.3048)
			(stroke
				(width 0.1)
				(type default)
			)
			(layer "F.Fab")
		)
		(fp_line
			(start 0.67945 -0.3048)
			(end 0.67945 0.3048)
			(stroke
				(width 0.1)
				(type default)
			)
			(layer "F.Fab")
		)
		(fp_line
			(start -0.67945 -0.305054)
			(end -0.12065 -0.305054)
			(stroke
				(width 0.1)
				(type default)
			)
			(layer "F.Fab")
		)
		(fp_line
			(start -0.12065 -0.305054)
			(end -0.12065 -0.2794)
			(stroke
				(width 0.1)
				(type default)
			)
			(layer "F.Fab")
		)
		(pad "1" smd circle
			(at -0.40005 0 270)
			(size 0 0)
			(layers "F.Cu" "F.Mask" "F.Paste")
			(net "USB_HUB2_TI_GRSTZ_MRP_PROG_FUNC1")
		)
		(pad "2" smd circle
			(at 0.40005 0 270)
			(size 0 0)
			(layers "F.Cu" "F.Mask" "F.Paste")
			(net "GND")
		)
	)
	(footprint ""
		(layer "F.Cu")
		(at 368.06378 -427.411388 -90)
		(property "Reference" "R4198"
			(at 0 0 270)
			(layer "F.SilkS")
			(hide yes)
			(effects
				(font
					(size 1.27 1.27)
				)
			)
		)
		(property "Value" ""
			(at 0 0 270)
			(layer "F.Fab")
			(effects
				(font
					(size 1.27 1.27)
				)
			)
		)
		(duplicate_pad_numbers_are_jumpers no)
		(fp_line
			(start -0.7874 0.4064)
			(end -0.7874 -0.4064)
			(stroke
				(width 0.1524)
				(type default)
			)
			(layer "F.SilkS")
		)
		(fp_line
			(start 0.7874 0.4064)
			(end -0.7874 0.4064)
			(stroke
				(width 0.1524)
				(type default)
			)
			(layer "F.SilkS")
		)
		(fp_line
			(start -0.7874 -0.4064)
			(end 0.7874 -0.4064)
			(stroke
				(width 0.1524)
				(type default)
			)
			(layer "F.SilkS")
		)
		(fp_line
			(start 0.7874 -0.4064)
			(end 0.7874 0.4064)
			(stroke
				(width 0.1524)
				(type default)
			)
			(layer "F.SilkS")
		)
		(fp_line
			(start -0.67945 0.3048)
			(end -0.67945 -0.305054)
			(stroke
				(width 0.1)
				(type default)
			)
			(layer "F.Fab")
		)
		(fp_line
			(start -0.12065 0.3048)
			(end -0.67945 0.3048)
			(stroke
				(width 0.1)
				(type default)
			)
			(layer "F.Fab")
		)
		(fp_line
			(start 0.120396 0.3048)
			(end 0.120396 0.2794)
			(stroke
				(width 0.1)
				(type default)
			)
			(layer "F.Fab")
		)
		(fp_line
			(start 0.67945 0.3048)
			(end 0.120396 0.3048)
			(stroke
				(width 0.1)
				(type default)
			)
			(layer "F.Fab")
		)
		(fp_line
			(start -0.12065 0.2794)
			(end -0.12065 0.3048)
			(stroke
				(width 0.1)
				(type default)
			)
			(layer "F.Fab")
		)
		(fp_line
			(start 0.120396 0.2794)
			(end -0.12065 0.2794)
			(stroke
				(width 0.1)
				(type default)
			)
			(layer "F.Fab")
		)
		(fp_line
			(start -0.12065 -0.2794)
			(end 0.12065 -0.2794)
			(stroke
				(width 0.1)
				(type default)
			)
			(layer "F.Fab")
		)
		(fp_line
			(start 0.12065 -0.2794)
			(end 0.12065 -0.3048)
			(stroke
				(width 0.1)
				(type default)
			)
			(layer "F.Fab")
		)
		(fp_line
			(start 0.12065 -0.3048)
			(end 0.67945 -0.3048)
			(stroke
				(width 0.1)
				(type default)
			)
			(layer "F.Fab")
		)
		(fp_line
			(start 0.67945 -0.3048)
			(end 0.67945 0.3048)
			(stroke
				(width 0.1)
				(type default)
			)
			(layer "F.Fab")
		)
		(fp_line
			(start -0.67945 -0.305054)
			(end -0.12065 -0.305054)
			(stroke
				(width 0.1)
				(type default)
			)
			(layer "F.Fab")
		)
		(fp_line
			(start -0.12065 -0.305054)
			(end -0.12065 -0.2794)
			(stroke
				(width 0.1)
				(type default)
			)
			(layer "F.Fab")
		)
		(pad "1" smd circle
			(at -0.40005 0 270)
			(size 0 0)
			(layers "F.Cu" "F.Mask" "F.Paste")
			(net "P3V3_AUX")
		)
		(pad "2" smd circle
			(at 0.40005 0 270)
			(size 0 0)
			(layers "F.Cu" "F.Mask" "F.Paste")
			(net "U270_0_ADD1")
		)
	)
)
